(kicad_pcb
	(version 20260206)
	(generator "pcbnew")
	(generator_version "10.0")
	(general
		(thickness 1.6)
		(legacy_teardrops no)
	)
	(paper "A4")
	(title_block
		(title "01162023_DA0F0TEBIF0_F0T_Expander_BD_F_brd_V02_OCP.brd")
		(comment 1 "Grand Teton / footprints 2282-2286 of 9728")
	)
	(layers
		(0 "F.Cu" signal "TOP")
		(4 "In1.Cu" signal "GND")
		(6 "In2.Cu" signal "VCC")
		(8 "In3.Cu" signal "VCC1")
		(10 "In4.Cu" signal "GND1")
		(12 "In5.Cu" signal "IN1")
		(14 "In6.Cu" signal "GND2")
		(16 "In7.Cu" signal "IN2")
		(18 "In8.Cu" signal "GND3")
		(20 "In9.Cu" signal "IN3")
		(22 "In10.Cu" signal "GND4")
		(24 "In11.Cu" signal "IN4")
		(26 "In12.Cu" signal "GND5")
		(28 "In13.Cu" signal "IN5")
		(30 "In14.Cu" signal "GND6")
		(32 "In15.Cu" signal "IN6")
		(34 "In16.Cu" signal "GND7")
		(2 "B.Cu" signal "BOTTOM")
		(9 "F.Adhes" user "F.Adhesive")
		(11 "B.Adhes" user "B.Adhesive")
		(13 "F.Paste" user "Package Geometry/Pastemask Top")
		(15 "B.Paste" user "Package Geometry/Pastemask Bottom")
		(5 "F.SilkS" user "Ref Des/Silkscreen Top")
		(7 "B.SilkS" user "Ref Des/Silkscreen Bottom")
		(1 "F.Mask" user "Board Geometry/Soldermask Top")
		(3 "B.Mask" user "Board Geometry/Soldermask Bottom")
		(17 "Dwgs.User" user "User.Drawings")
		(19 "Cmts.User" user "User.Comments")
		(21 "Eco1.User" user "User.Eco1")
		(23 "Eco2.User" user "User.Eco2")
		(25 "Edge.Cuts" user "Board Geometry/Outline")
		(27 "Margin" user)
		(31 "F.CrtYd" user "Package Geometry/Place Bound Top")
		(29 "B.CrtYd" user "Package Geometry/Place Bound Bottom")
		(35 "F.Fab" user "Ref Des/Assembly Top")
		(33 "B.Fab" user "Ref Des/Assembly Bottom")
	)
	(footprint ""
		(layer "F.Cu")
		(at 214.908892 -104.962198 90)
		(property "Reference" "R722"
			(at 0 0 90)
			(layer "F.SilkS")
			(hide yes)
			(effects
				(font
					(size 1.27 1.27)
				)
			)
		)
		(property "Value" ""
			(at 0 0 90)
			(layer "F.Fab")
			(effects
				(font
					(size 1.27 1.27)
				)
			)
		)
		(duplicate_pad_numbers_are_jumpers no)
		(fp_line
			(start 0.7874 -0.4064)
			(end 0.7874 0.4064)
			(stroke
				(width 0.1524)
				(type default)
			)
			(layer "F.SilkS")
		)
		(fp_line
			(start -0.7874 -0.4064)
			(end 0.7874 -0.4064)
			(stroke
				(width 0.1524)
				(type default)
			)
			(layer "F.SilkS")
		)
		(fp_line
			(start 0.7874 0.4064)
			(end -0.7874 0.4064)
			(stroke
				(width 0.1524)
				(type default)
			)
			(layer "F.SilkS")
		)
		(fp_line
			(start -0.7874 0.4064)
			(end -0.7874 -0.4064)
			(stroke
				(width 0.1524)
				(type default)
			)
			(layer "F.SilkS")
		)
		(fp_line
			(start -0.12065 -0.305054)
			(end -0.12065 -0.2794)
			(stroke
				(width 0.1)
				(type default)
			)
			(layer "F.Fab")
		)
		(fp_line
			(start -0.67945 -0.305054)
			(end -0.12065 -0.305054)
			(stroke
				(width 0.1)
				(type default)
			)
			(layer "F.Fab")
		)
		(fp_line
			(start 0.67945 -0.3048)
			(end 0.67945 0.3048)
			(stroke
				(width 0.1)
				(type default)
			)
			(layer "F.Fab")
		)
		(fp_line
			(start 0.12065 -0.3048)
			(end 0.67945 -0.3048)
			(stroke
				(width 0.1)
				(type default)
			)
			(layer "F.Fab")
		)
		(fp_line
			(start 0.12065 -0.2794)
			(end 0.12065 -0.3048)
			(stroke
				(width 0.1)
				(type default)
			)
			(layer "F.Fab")
		)
		(fp_line
			(start -0.12065 -0.2794)
			(end 0.12065 -0.2794)
			(stroke
				(width 0.1)
				(type default)
			)
			(layer "F.Fab")
		)
		(fp_line
			(start 0.120396 0.2794)
			(end -0.12065 0.2794)
			(stroke
				(width 0.1)
				(type default)
			)
			(layer "F.Fab")
		)
		(fp_line
			(start -0.12065 0.2794)
			(end -0.12065 0.3048)
			(stroke
				(width 0.1)
				(type default)
			)
			(layer "F.Fab")
		)
		(fp_line
			(start 0.67945 0.3048)
			(end 0.120396 0.3048)
			(stroke
				(width 0.1)
				(type default)
			)
			(layer "F.Fab")
		)
		(fp_line
			(start 0.120396 0.3048)
			(end 0.120396 0.2794)
			(stroke
				(width 0.1)
				(type default)
			)
			(layer "F.Fab")
		)
		(fp_line
			(start -0.12065 0.3048)
			(end -0.67945 0.3048)
			(stroke
				(width 0.1)
				(type default)
			)
			(layer "F.Fab")
		)
		(fp_line
			(start -0.67945 0.3048)
			(end -0.67945 -0.305054)
			(stroke
				(width 0.1)
				(type default)
			)
			(layer "F.Fab")
		)
		(pad "1" smd circle
			(at -0.40005 0 90)
			(size 0 0)
			(layers "F.Cu" "F.Mask" "F.Paste")
			(net "P12V_NIC3_R")
		)
		(pad "2" smd circle
			(at 0.40005 0 90)
			(size 0 0)
			(layers "F.Cu" "F.Mask" "F.Paste")
			(net "P12V_NIC3_VIN_P")
		)
	)
	(footprint ""
		(layer "F.Cu")
		(at 94.494096 -117.426486)
		(property "Reference" "PC666"
			(at 0 0 0)
			(layer "F.SilkS")
			(hide yes)
			(effects
				(font
					(size 1.27 1.27)
				)
			)
		)
		(property "Value" ""
			(at 0 0 0)
			(layer "F.Fab")
			(effects
				(font
					(size 1.27 1.27)
				)
			)
		)
		(duplicate_pad_numbers_are_jumpers no)
		(fp_line
			(start -0.7874 -0.4064)
			(end 0.7874 -0.4064)
			(stroke
				(width 0.1524)
				(type default)
			)
			(layer "F.SilkS")
		)
		(fp_line
			(start -0.7874 0.4064)
			(end -0.7874 -0.4064)
			(stroke
				(width 0.1524)
				(type default)
			)
			(layer "F.SilkS")
		)
		(fp_line
			(start 0.7874 -0.4064)
			(end 0.7874 0.4064)
			(stroke
				(width 0.1524)
				(type default)
			)
			(layer "F.SilkS")
		)
		(fp_line
			(start 0.7874 0.4064)
			(end -0.7874 0.4064)
			(stroke
				(width 0.1524)
				(type default)
			)
			(layer "F.SilkS")
		)
		(fp_line
			(start -0.67945 -0.305054)
			(end -0.12065 -0.305054)
			(stroke
				(width 0.1)
				(type default)
			)
			(layer "F.Fab")
		)
		(fp_line
			(start -0.67945 0.3048)
			(end -0.67945 -0.305054)
			(stroke
				(width 0.1)
				(type default)
			)
			(layer "F.Fab")
		)
		(fp_line
			(start -0.12065 -0.305054)
			(end -0.12065 -0.2794)
			(stroke
				(width 0.1)
				(type default)
			)
			(layer "F.Fab")
		)
		(fp_line
			(start -0.12065 -0.2794)
			(end 0.12065 -0.2794)
			(stroke
				(width 0.1)
				(type default)
			)
			(layer "F.Fab")
		)
		(fp_line
			(start -0.12065 0.2794)
			(end -0.12065 0.3048)
			(stroke
				(width 0.1)
				(type default)
			)
			(layer "F.Fab")
		)
		(fp_line
			(start -0.12065 0.3048)
			(end -0.67945 0.3048)
			(stroke
				(width 0.1)
				(type default)
			)
			(layer "F.Fab")
		)
		(fp_line
			(start 0.120396 0.2794)
			(end -0.12065 0.2794)
			(stroke
				(width 0.1)
				(type default)
			)
			(layer "F.Fab")
		)
		(fp_line
			(start 0.120396 0.3048)
			(end 0.120396 0.2794)
			(stroke
				(width 0.1)
				(type default)
			)
			(layer "F.Fab")
		)
		(fp_line
			(start 0.12065 -0.3048)
			(end 0.67945 -0.3048)
			(stroke
				(width 0.1)
				(type default)
			)
			(layer "F.Fab")
		)
		(fp_line
			(start 0.12065 -0.2794)
			(end 0.12065 -0.3048)
			(stroke
				(width 0.1)
				(type default)
			)
			(layer "F.Fab")
		)
		(fp_line
			(start 0.67945 -0.3048)
			(end 0.67945 0.3048)
			(stroke
				(width 0.1)
				(type default)
			)
			(layer "F.Fab")
		)
		(fp_line
			(start 0.67945 0.3048)
			(end 0.120396 0.3048)
			(stroke
				(width 0.1)
				(type default)
			)
			(layer "F.Fab")
		)
		(pad "1" smd circle
			(at -0.40005 0)
			(size 0 0)
			(layers "F.Cu" "F.Mask" "F.Paste")
			(net "P3V3_NIC1_CO_MODE")
		)
		(pad "2" smd circle
			(at 0.40005 0)
			(size 0 0)
			(layers "F.Cu" "F.Mask" "F.Paste")
			(net "GND")
		)
	)
	(footprint ""
		(layer "F.Cu")
		(at 324.249542 -304.036476 90)
		(property "Reference" "R1389"
			(at 0 0 90)
			(layer "F.SilkS")
			(hide yes)
			(effects
				(font
					(size 1.27 1.27)
				)
			)
		)
		(property "Value" ""
			(at 0 0 90)
			(layer "F.Fab")
			(effects
				(font
					(size 1.27 1.27)
				)
			)
		)
		(duplicate_pad_numbers_are_jumpers no)
		(fp_line
			(start 0.7874 -0.4064)
			(end 0.7874 0.4064)
			(stroke
				(width 0.1524)
				(type default)
			)
			(layer "F.SilkS")
		)
		(fp_line
			(start -0.7874 -0.4064)
			(end 0.7874 -0.4064)
			(stroke
				(width 0.1524)
				(type default)
			)
			(layer "F.SilkS")
		)
		(fp_line
			(start 0.7874 0.4064)
			(end -0.7874 0.4064)
			(stroke
				(width 0.1524)
				(type default)
			)
			(layer "F.SilkS")
		)
		(fp_line
			(start -0.7874 0.4064)
			(end -0.7874 -0.4064)
			(stroke
				(width 0.1524)
				(type default)
			)
			(layer "F.SilkS")
		)
		(fp_line
			(start -0.12065 -0.305054)
			(end -0.12065 -0.2794)
			(stroke
				(width 0.1)
				(type default)
			)
			(layer "F.Fab")
		)
		(fp_line
			(start -0.67945 -0.305054)
			(end -0.12065 -0.305054)
			(stroke
				(width 0.1)
				(type default)
			)
			(layer "F.Fab")
		)
		(fp_line
			(start 0.67945 -0.3048)
			(end 0.67945 0.3048)
			(stroke
				(width 0.1)
				(type default)
			)
			(layer "F.Fab")
		)
		(fp_line
			(start 0.12065 -0.3048)
			(end 0.67945 -0.3048)
			(stroke
				(width 0.1)
				(type default)
			)
			(layer "F.Fab")
		)
		(fp_line
			(start 0.12065 -0.2794)
			(end 0.12065 -0.3048)
			(stroke
				(width 0.1)
				(type default)
			)
			(layer "F.Fab")
		)
		(fp_line
			(start -0.12065 -0.2794)
			(end 0.12065 -0.2794)
			(stroke
				(width 0.1)
				(type default)
			)
			(layer "F.Fab")
		)
		(fp_line
			(start 0.120396 0.2794)
			(end -0.12065 0.2794)
			(stroke
				(width 0.1)
				(type default)
			)
			(layer "F.Fab")
		)
		(fp_line
			(start -0.12065 0.2794)
			(end -0.12065 0.3048)
			(stroke
				(width 0.1)
				(type default)
			)
			(layer "F.Fab")
		)
		(fp_line
			(start 0.67945 0.3048)
			(end 0.120396 0.3048)
			(stroke
				(width 0.1)
				(type default)
			)
			(layer "F.Fab")
		)
		(fp_line
			(start 0.120396 0.3048)
			(end 0.120396 0.2794)
			(stroke
				(width 0.1)
				(type default)
			)
			(layer "F.Fab")
		)
		(fp_line
			(start -0.12065 0.3048)
			(end -0.67945 0.3048)
			(stroke
				(width 0.1)
				(type default)
			)
			(layer "F.Fab")
		)
		(fp_line
			(start -0.67945 0.3048)
			(end -0.67945 -0.305054)
			(stroke
				(width 0.1)
				(type default)
			)
			(layer "F.Fab")
		)
		(pad "1" smd circle
			(at -0.40005 0 90)
			(size 0 0)
			(layers "F.Cu" "F.Mask" "F.Paste")
			(net "GND")
		)
		(pad "2" smd circle
			(at 0.40005 0 90)
			(size 0 0)
			(layers "F.Cu" "F.Mask" "F.Paste")
			(net "PEX2_SPARE6")
		)
	)
	(footprint ""
		(layer "F.Cu")
		(at 278.131778 -410.014928 -90)
		(property "Reference" "U308"
			(at -0.56134 -2.822956 90)
			(unlocked yes)
			(layer "F.SilkS")
			(effects
				(font
					(size 0.7874 0.5842)
					(thickness 0.1524)
				)
			)
		)
		(property "Value" ""
			(at 0 0 270)
			(layer "F.Fab")
			(effects
				(font
					(size 1.27 1.27)
				)
			)
		)
		(duplicate_pad_numbers_are_jumpers no)
		(fp_line
			(start -1.0414 1.575054)
			(end -1.0414 -1.575054)
			(stroke
				(width 0.1524)
				(type default)
			)
			(layer "F.SilkS")
		)
		(fp_line
			(start 1.0414 1.575054)
			(end -1.0414 1.575054)
			(stroke
				(width 0.1524)
				(type default)
			)
			(layer "F.SilkS")
		)
		(fp_line
			(start 0 -1.272032)
			(end -0.254 -1.575054)
			(stroke
				(width 0.1524)
				(type default)
			)
			(layer "F.SilkS")
		)
		(fp_line
			(start -1.0414 -1.575054)
			(end -0.254 -1.575054)
			(stroke
				(width 0.1524)
				(type default)
			)
			(layer "F.SilkS")
		)
		(fp_line
			(start 0.2286 -1.575054)
			(end 0 -1.272032)
			(stroke
				(width 0.1524)
				(type default)
			)
			(layer "F.SilkS")
		)
		(fp_line
			(start 0.254 -1.575054)
			(end 1.0414 -1.575054)
			(stroke
				(width 0.1524)
				(type default)
			)
			(layer "F.SilkS")
		)
		(fp_line
			(start 1.0414 -1.575054)
			(end 1.0414 1.575054)
			(stroke
				(width 0.1524)
				(type default)
			)
			(layer "F.SilkS")
		)
		(fp_poly
			(pts
				(xy -2.710688 -0.975106) (xy -3.726688 -1.483106) (xy -3.726688 -0.467106)
			)
			(stroke
				(width 0)
				(type default)
			)
			(fill yes)
			(layer "F.SilkS")
		)
		(fp_line
			(start -1.4478 1.5748)
			(end -1.4478 1.2192)
			(stroke
				(width 0.1)
				(type default)
			)
			(layer "F.Fab")
		)
		(fp_line
			(start 1.4478 1.5748)
			(end -1.4478 1.5748)
			(stroke
				(width 0.1)
				(type default)
			)
			(layer "F.Fab")
		)
		(fp_line
			(start -2.5654 1.2192)
			(end -2.5654 -1.2192)
			(stroke
				(width 0.1)
				(type default)
			)
			(layer "F.Fab")
		)
		(fp_line
			(start -1.4478 1.2192)
			(end -2.5654 1.2192)
			(stroke
				(width 0.1)
				(type default)
			)
			(layer "F.Fab")
		)
		(fp_line
			(start 1.4478 1.2192)
			(end 1.4478 1.5748)
			(stroke
				(width 0.1)
				(type default)
			)
			(layer "F.Fab")
		)
		(fp_line
			(start 2.5654 1.2192)
			(end 1.4478 1.2192)
			(stroke
				(width 0.1)
				(type default)
			)
			(layer "F.Fab")
		)
		(fp_line
			(start -2.5654 -1.2192)
			(end -1.4478 -1.2192)
			(stroke
				(width 0.1)
				(type default)
			)
			(layer "F.Fab")
		)
		(fp_line
			(start -1.4478 -1.2192)
			(end -1.4478 -1.5748)
			(stroke
				(width 0.1)
				(type default)
			)
			(layer "F.Fab")
		)
		(fp_line
			(start 1.4478 -1.2192)
			(end 2.5654 -1.2192)
			(stroke
				(width 0.1)
				(type default)
			)
			(layer "F.Fab")
		)
		(fp_line
			(start 2.5654 -1.2192)
			(end 2.5654 1.2192)
			(stroke
				(width 0.1)
				(type default)
			)
			(layer "F.Fab")
		)
		(fp_line
			(start -1.4478 -1.5748)
			(end 1.4478 -1.5748)
			(stroke
				(width 0.1)
				(type default)
			)
			(layer "F.Fab")
		)
		(fp_line
			(start 1.4478 -1.5748)
			(end 1.4478 -1.2192)
			(stroke
				(width 0.1)
				(type default)
			)
			(layer "F.Fab")
		)
		(fp_poly
			(pts
				(xy -2.710688 -0.975106) (xy -3.726688 -1.483106) (xy -3.726688 -0.467106)
			)
			(stroke
				(width 0)
				(type default)
			)
			(fill yes)
			(layer "F.Fab")
		)
		(pad "1" smd rect
			(at -1.849882 -0.975106 180)
			(size 0.3556 1.3208)
			(layers "F.Cu" "F.Mask" "F.Paste")
			(net "MB_BIC_R_MON")
		)
		(pad "2" smd rect
			(at -1.849882 -0.32512 180)
			(size 0.3556 1.3208)
			(layers "F.Cu" "F.Mask" "F.Paste")
			(net "MB_BIC_READY_BUF_N")
		)
		(pad "3" smd rect
			(at -1.849882 0.32512 180)
			(size 0.3556 1.3208)
			(layers "F.Cu" "F.Mask" "F.Paste")
			(net "RST_MB_BMC_R_N")
		)
		(pad "4" smd rect
			(at -1.849882 0.975106 180)
			(size 0.3556 1.3208)
			(layers "F.Cu" "F.Mask" "F.Paste")
			(net "GND")
		)
		(pad "5" smd rect
			(at 1.849882 0.975106 180)
			(size 0.3556 1.3208)
			(layers "F.Cu" "F.Mask" "F.Paste")
			(net "RST_MB_BMC_BUF_N")
		)
		(pad "6" smd rect
			(at 1.849882 0.32512 180)
			(size 0.3556 1.3208)
			(layers "F.Cu" "F.Mask" "F.Paste")
			(net "BIC_SYS_READY_R1_N")
		)
		(pad "7" smd rect
			(at 1.849882 -0.32512 180)
			(size 0.3556 1.3208)
			(layers "F.Cu" "F.Mask" "F.Paste")
			(net "MB_BIC_MON_BUF")
		)
		(pad "8" smd rect
			(at 1.849882 -0.975106 180)
			(size 0.3556 1.3208)
			(layers "F.Cu" "F.Mask" "F.Paste")
			(net "P3V3_AUX")
		)
	)
	(footprint ""
		(layer "F.Cu")
		(at 239.812322 -60.163964 180)
		(property "Reference" "R5998"
			(at 0 0 180)
			(layer "F.SilkS")
			(hide yes)
			(effects
				(font
					(size 1.27 1.27)
				)
			)
		)
		(property "Value" ""
			(at 0 0 180)
			(layer "F.Fab")
			(effects
				(font
					(size 1.27 1.27)
				)
			)
		)
		(duplicate_pad_numbers_are_jumpers no)
		(fp_line
			(start 0.7874 0.4064)
			(end -0.7874 0.4064)
			(stroke
				(width 0.1524)
				(type default)
			)
			(layer "F.SilkS")
		)
		(fp_line
			(start 0.7874 -0.4064)
			(end 0.7874 0.4064)
			(stroke
				(width 0.1524)
				(type default)
			)
			(layer "F.SilkS")
		)
		(fp_line
			(start -0.7874 0.4064)
			(end -0.7874 -0.4064)
			(stroke
				(width 0.1524)
				(type default)
			)
			(layer "F.SilkS")
		)
		(fp_line
			(start -0.7874 -0.4064)
			(end 0.7874 -0.4064)
			(stroke
				(width 0.1524)
				(type default)
			)
			(layer "F.SilkS")
		)
		(fp_line
			(start 0.67945 0.3048)
			(end 0.120396 0.3048)
			(stroke
				(width 0.1)
				(type default)
			)
			(layer "F.Fab")
		)
		(fp_line
			(start 0.67945 -0.3048)
			(end 0.67945 0.3048)
			(stroke
				(width 0.1)
				(type default)
			)
			(layer "F.Fab")
		)
		(fp_line
			(start 0.12065 -0.2794)
			(end 0.12065 -0.3048)
			(stroke
				(width 0.1)
				(type default)
			)
			(layer "F.Fab")
		)
		(fp_line
			(start 0.12065 -0.3048)
			(end 0.67945 -0.3048)
			(stroke
				(width 0.1)
				(type default)
			)
			(layer "F.Fab")
		)
		(fp_line
			(start 0.120396 0.3048)
			(end 0.120396 0.2794)
			(stroke
				(width 0.1)
				(type default)
			)
			(layer "F.Fab")
		)
		(fp_line
			(start 0.120396 0.2794)
			(end -0.12065 0.2794)
			(stroke
				(width 0.1)
				(type default)
			)
			(layer "F.Fab")
		)
		(fp_line
			(start -0.12065 0.3048)
			(end -0.67945 0.3048)
			(stroke
				(width 0.1)
				(type default)
			)
			(layer "F.Fab")
		)
		(fp_line
			(start -0.12065 0.2794)
			(end -0.12065 0.3048)
			(stroke
				(width 0.1)
				(type default)
			)
			(layer "F.Fab")
		)
		(fp_line
			(start -0.12065 -0.2794)
			(end 0.12065 -0.2794)
			(stroke
				(width 0.1)
				(type default)
			)
			(layer "F.Fab")
		)
		(fp_line
			(start -0.12065 -0.305054)
			(end -0.12065 -0.2794)
			(stroke
				(width 0.1)
				(type default)
			)
			(layer "F.Fab")
		)
		(fp_line
			(start -0.67945 0.3048)
			(end -0.67945 -0.305054)
			(stroke
				(width 0.1)
				(type default)
			)
			(layer "F.Fab")
		)
		(fp_line
			(start -0.67945 -0.305054)
			(end -0.12065 -0.305054)
			(stroke
				(width 0.1)
				(type default)
			)
			(layer "F.Fab")
		)
		(pad "1" smd circle
			(at -0.40005 0 180)
			(size 0 0)
			(layers "F.Cu" "F.Mask" "F.Paste")
			(net "P12V_SSD8_R")
		)
		(pad "2" smd circle
			(at 0.40005 0 180)
			(size 0 0)
			(layers "F.Cu" "F.Mask" "F.Paste")
			(net "P12V_SSD8_PG_G1")
		)
	)
)
